(kicad_pcb
	(version 20240108)
	(generator "pcbnew")
	(generator_version "8.0")
	(general
		(thickness 1.62)
		(legacy_teardrops no)
	)
	(paper "A4")
	(title_block
		(title "Jetson Orin Baseboard")
		(date "2025-03-12")
		(rev "1.3.4")
		(company "Antmicro Ltd")
		(comment 1 "www.antmicro.com")
		(comment 9 "footprints 542-546 of 677")
	)
	(layers
		(0 "F.Cu" signal)
		(1 "In1.Cu" signal)
		(2 "In2.Cu" signal)
		(3 "In3.Cu" signal)
		(4 "In4.Cu" jumper)
		(5 "In5.Cu" signal)
		(6 "In6.Cu" signal)
		(31 "B.Cu" signal)
		(32 "B.Adhes" user "B.Adhesive")
		(33 "F.Adhes" user "F.Adhesive")
		(34 "B.Paste" user)
		(35 "F.Paste" user)
		(36 "B.SilkS" user "B.Silkscreen")
		(37 "F.SilkS" user "F.Silkscreen")
		(38 "B.Mask" user)
		(39 "F.Mask" user)
		(40 "Dwgs.User" user "User.Drawings")
		(41 "Cmts.User" user "User.Comments")
		(42 "Eco1.User" user "User.Eco1")
		(43 "Eco2.User" user "User.Eco2")
		(44 "Edge.Cuts" user)
		(45 "Margin" user)
		(46 "B.CrtYd" user "B.Courtyard")
		(47 "F.CrtYd" user "F.Courtyard")
		(48 "B.Fab" user)
		(49 "F.Fab" user)
	)
	(footprint "antmicro-footprints:XSON-8_1x1.95mm_P0.5mm"
		(layer "B.Cu")
		(at 139 98.8025 90)
		(property "Reference" "U31"
			(at 0.8625 2.2 -90)
			(layer "B.SilkS")
			(effects
				(font
					(size 0.7 0.7)
					(thickness 0.15)
				)
				(justify left bottom mirror)
			)
		)
		(property "Value" "NTS0102_XSON"
			(at 0 -2.2 -90)
			(layer "B.Fab")
			(effects
				(font
					(size 0.7 0.7)
					(thickness 0.15)
				)
				(justify left bottom mirror)
			)
		)
		(property "Footprint" "antmicro-footprints:XSON-8_1x1.95mm_P0.5mm"
			(at 0 0 90)
			(layer "F.Fab")
			(hide yes)
			(effects
				(font
					(size 1.27 1.27)
					(thickness 0.15)
				)
			)
		)
		(property "Datasheet" "http://www.farnell.com/datasheets/1760723.pdf"
			(at 0 0 90)
			(layer "F.Fab")
			(hide yes)
			(effects
				(font
					(size 1.27 1.27)
					(thickness 0.15)
				)
			)
		)
		(property "Author" "Antmicro"
			(at 237.8025 -40.1975 0)
			(layer "B.Fab")
			(hide yes)
			(effects
				(font
					(size 1 1)
					(thickness 0.15)
				)
				(justify mirror)
			)
		)
		(property "License" "Apache-2.0"
			(at 237.8025 -40.1975 0)
			(layer "B.Fab")
			(hide yes)
			(effects
				(font
					(size 1 1)
					(thickness 0.15)
				)
				(justify mirror)
			)
		)
		(property "MPN" "NTS0102GT"
			(at 237.8025 -40.1975 0)
			(layer "B.Fab")
			(hide yes)
			(effects
				(font
					(size 1 1)
					(thickness 0.15)
				)
				(justify mirror)
			)
		)
		(property "Manufacturer" "NXP"
			(at 237.8025 -40.1975 0)
			(layer "B.Fab")
			(hide yes)
			(effects
				(font
					(size 1 1)
					(thickness 0.15)
				)
				(justify mirror)
			)
		)
		(sheetname "CSI")
		(sheetfile "csi.kicad_sch")
		(attr smd)
		(fp_line
			(start -0.5 -1.1)
			(end 0.5 -1.1)
			(stroke
				(width 0.15)
				(type solid)
			)
			(layer "B.SilkS")
		)
		(fp_line
			(start 0.5 1.1)
			(end -0.5 1.1)
			(stroke
				(width 0.15)
				(type solid)
			)
			(layer "B.SilkS")
		)
		(fp_circle
			(center -0.75 1.1)
			(end -0.701 1.1)
			(stroke
				(width 0.15)
				(type solid)
			)
			(fill none)
			(layer "B.SilkS")
		)
		(fp_rect
			(start -0.8 1.2)
			(end 0.8 -1.2)
			(stroke
				(width 0.05)
				(type solid)
			)
			(fill none)
			(layer "B.CrtYd")
		)
		(fp_line
			(start 0.5305 -1)
			(end 0.5305 1.001)
			(stroke
				(width 0.15)
				(type solid)
			)
			(layer "B.Fab")
		)
		(fp_line
			(start -0.5305 -1)
			(end 0.5305 -1)
			(stroke
				(width 0.15)
				(type solid)
			)
			(layer "B.Fab")
		)
		(fp_line
			(start 0.5305 1.001)
			(end -0.5305 1.001)
			(stroke
				(width 0.15)
				(type solid)
			)
			(layer "B.Fab")
		)
		(fp_line
			(start -0.5305 1.001)
			(end -0.5305 -1)
			(stroke
				(width 0.15)
				(type solid)
			)
			(layer "B.Fab")
		)
		(fp_text user "License: Apache-2.0"
			(at -0.527 -8.306 -90)
			(layer "B.Fab")
			(hide yes)
			(effects
				(font
					(size 0.7 0.7)
					(thickness 0.15)
				)
				(justify left bottom mirror)
			)
		)
		(fp_text user "${REFERENCE}"
			(at -0.527 -5.905 -90)
			(layer "B.Fab")
			(hide yes)
			(effects
				(font
					(size 0.7 0.7)
					(thickness 0.15)
				)
				(justify left bottom mirror)
			)
		)
		(fp_text user "Author: Antmicro"
			(at -0.527 -7.105 -90)
			(layer "B.Fab")
			(hide yes)
			(effects
				(font
					(size 0.7 0.7)
					(thickness 0.15)
				)
				(justify left bottom mirror)
			)
		)
		(pad "1" smd roundrect
			(at -0.45 0.75 270)
			(size 0.6 0.3)
			(layers "B.Cu" "B.Paste" "B.Mask")
			(roundrect_rratio 0.25)
			(net 371 "/CSI/VSYNC_CAM1_3V3")
			(pinfunction "B_{2}")
			(pintype "bidirectional")
		)
		(pad "2" smd roundrect
			(at -0.45 0.25 270)
			(size 0.6 0.25)
			(layers "B.Cu" "B.Paste" "B.Mask")
			(roundrect_rratio 0.25)
			(net 1 "GND")
			(pinfunction "GND")
			(pintype "power_in")
		)
		(pad "3" smd roundrect
			(at -0.45 -0.25 270)
			(size 0.6 0.25)
			(layers "B.Cu" "B.Paste" "B.Mask")
			(roundrect_rratio 0.25)
			(net 112 "+1V8")
			(pinfunction "VCC_{A}")
			(pintype "power_in")
		)
		(pad "4" smd roundrect
			(at -0.45 -0.75 270)
			(size 0.6 0.3)
			(layers "B.Cu" "B.Paste" "B.Mask")
			(roundrect_rratio 0.25)
			(net 219 "VSYNC_CAM1")
			(pinfunction "A_{2}")
			(pintype "bidirectional")
		)
		(pad "5" smd roundrect
			(at 0.45 -0.75 270)
			(size 0.6 0.3)
			(layers "B.Cu" "B.Paste" "B.Mask")
			(roundrect_rratio 0.25)
			(net 217 "VSYNC_CAM0")
			(pinfunction "A_{1}")
			(pintype "bidirectional")
		)
		(pad "6" smd roundrect
			(at 0.45 -0.25 270)
			(size 0.6 0.25)
			(layers "B.Cu" "B.Paste" "B.Mask")
			(roundrect_rratio 0.25)
			(net 112 "+1V8")
			(pinfunction "OE")
			(pintype "input")
		)
		(pad "7" smd roundrect
			(at 0.45 0.25 270)
			(size 0.6 0.25)
			(layers "B.Cu" "B.Paste" "B.Mask")
			(roundrect_rratio 0.25)
			(net 87 "+3V3")
			(pinfunction "VCC_{B}")
			(pintype "power_in")
		)
		(pad "8" smd roundrect
			(at 0.45 0.75 270)
			(size 0.6 0.3)
			(layers "B.Cu" "B.Paste" "B.Mask")
			(roundrect_rratio 0.25)
			(net 360 "/CSI/VSYNC_CAM0_3V3")
			(pinfunction "B_{1}")
			(pintype "bidirectional")
		)
	)
	(footprint "antmicro-footprints:R_0402_1005Metric"
		(layer "B.Cu")
		(at 46.9 87.6375)
		(descr "Resistor SMD 0402")
		(tags "resistor SMD 0402")
		(property "Reference" "R123"
			(at 0.335 -3.4775 180)
			(layer "B.SilkS")
			(effects
				(font
					(size 0.7 0.7)
					(thickness 0.15)
				)
				(justify left bottom mirror)
			)
		)
		(property "Value" "R_1k3_0402"
			(at 0 -1.4 180)
			(layer "B.Fab")
			(effects
				(font
					(size 0.7 0.7)
					(thickness 0.15)
				)
				(justify left bottom mirror)
			)
		)
		(property "Footprint" "antmicro-footprints:R_0402_1005Metric"
			(at 0 0 0)
			(layer "F.Fab")
			(hide yes)
			(effects
				(font
					(size 1.27 1.27)
					(thickness 0.15)
				)
			)
		)
		(property "Datasheet" "https://www.bourns.com/docs/product-datasheets/cr.pdf"
			(at 0 0 0)
			(layer "F.Fab")
			(hide yes)
			(effects
				(font
					(size 1.27 1.27)
					(thickness 0.15)
				)
			)
		)
		(property "Author" "Antmicro"
			(at 0 0 0)
			(layer "B.Fab")
			(hide yes)
			(effects
				(font
					(size 1 1)
					(thickness 0.15)
				)
				(justify mirror)
			)
		)
		(property "License" "Apache-2.0"
			(at 0 0 0)
			(layer "B.Fab")
			(hide yes)
			(effects
				(font
					(size 1 1)
					(thickness 0.15)
				)
				(justify mirror)
			)
		)
		(property "MPN" "CR0402-FX-1301GLF"
			(at 0 0 0)
			(layer "B.Fab")
			(hide yes)
			(effects
				(font
					(size 1 1)
					(thickness 0.15)
				)
				(justify mirror)
			)
		)
		(property "Manufacturer" "Bourns"
			(at 0 0 0)
			(layer "B.Fab")
			(hide yes)
			(effects
				(font
					(size 1 1)
					(thickness 0.15)
				)
				(justify mirror)
			)
		)
		(property "Tolerance" "1%"
			(at 0 0 0)
			(layer "B.Fab")
			(hide yes)
			(effects
				(font
					(size 1 1)
					(thickness 0.15)
				)
				(justify mirror)
			)
		)
		(property "Val" "1k3"
			(at 0 0 0)
			(layer "B.Fab")
			(hide yes)
			(effects
				(font
					(size 1 1)
					(thickness 0.15)
				)
				(justify mirror)
			)
		)
		(sheetname "Ethernet")
		(sheetfile "ethernet.kicad_sch")
		(attr smd)
		(fp_rect
			(start -0.925 0.47)
			(end 0.925 -0.47)
			(stroke
				(width 0.05)
				(type default)
			)
			(fill none)
			(layer "B.CrtYd")
		)
		(fp_rect
			(start -0.5 0.25)
			(end 0.5 -0.25)
			(stroke
				(width 0.15)
				(type solid)
			)
			(fill none)
			(layer "B.Fab")
		)
		(fp_text user "Author: Antmicro"
			(at -0.95 -4.169 180)
			(layer "B.Fab")
			(hide yes)
			(effects
				(font
					(size 0.7 0.7)
					(thickness 0.15)
				)
				(justify left bottom mirror)
			)
		)
		(fp_text user "${REFERENCE}"
			(at -0.95 -3.168 180)
			(layer "B.Fab")
			(hide yes)
			(effects
				(font
					(size 0.7 0.7)
					(thickness 0.15)
				)
				(justify left bottom mirror)
			)
		)
		(fp_text user "License: Apache-2.0"
			(at -0.95 -5.169 180)
			(layer "B.Fab")
			(hide yes)
			(effects
				(font
					(size 0.7 0.7)
					(thickness 0.15)
				)
				(justify left bottom mirror)
			)
		)
		(pad "1" smd roundrect
			(at -0.48 0)
			(size 0.59 0.64)
			(layers "B.Cu" "B.Paste" "B.Mask")
			(roundrect_rratio 0.25)
			(net 499 "/Ethernet/VSS")
			(pintype "passive")
		)
		(pad "2" smd roundrect
			(at 0.48 0)
			(size 0.59 0.64)
			(layers "B.Cu" "B.Paste" "B.Mask")
			(roundrect_rratio 0.25)
			(net 565 "/Ethernet/AMPS_CTL")
			(pintype "passive")
		)
	)
	(footprint "antmicro-footprints:R_0402_1005Metric"
		(layer "B.Cu")
		(at 56.55 107.26)
		(descr "Resistor SMD 0402")
		(tags "resistor SMD 0402")
		(property "Reference" "R156"
			(at 0.97 1.31 180)
			(layer "B.SilkS")
			(effects
				(font
					(size 0.7 0.7)
					(thickness 0.15)
				)
				(justify left bottom mirror)
			)
		)
		(property "Value" "R_1k_0402"
			(at 0 -1.4 180)
			(layer "B.Fab")
			(effects
				(font
					(size 0.7 0.7)
					(thickness 0.15)
				)
				(justify left bottom mirror)
			)
		)
		(property "Footprint" "antmicro-footprints:R_0402_1005Metric"
			(at 0 0 0)
			(layer "F.Fab")
			(hide yes)
			(effects
				(font
					(size 1.27 1.27)
					(thickness 0.15)
				)
			)
		)
		(property "Datasheet" "https://www.bourns.com/docs/product-datasheets/cr.pdf"
			(at 0 0 0)
			(layer "F.Fab")
			(hide yes)
			(effects
				(font
					(size 1.27 1.27)
					(thickness 0.15)
				)
			)
		)
		(property "Author" "Antmicro"
			(at 0 0 0)
			(layer "B.Fab")
			(hide yes)
			(effects
				(font
					(size 1 1)
					(thickness 0.15)
				)
				(justify mirror)
			)
		)
		(property "License" "Apache-2.0"
			(at 0 0 0)
			(layer "B.Fab")
			(hide yes)
			(effects
				(font
					(size 1 1)
					(thickness 0.15)
				)
				(justify mirror)
			)
		)
		(property "MPN" "CR0402-FX-1001GLF"
			(at 0 0 0)
			(layer "B.Fab")
			(hide yes)
			(effects
				(font
					(size 1 1)
					(thickness 0.15)
				)
				(justify mirror)
			)
		)
		(property "Manufacturer" "Bourns"
			(at 0 0 0)
			(layer "B.Fab")
			(hide yes)
			(effects
				(font
					(size 1 1)
					(thickness 0.15)
				)
				(justify mirror)
			)
		)
		(property "Tolerance" "1%"
			(at 0 0 0)
			(layer "B.Fab")
			(hide yes)
			(effects
				(font
					(size 1 1)
					(thickness 0.15)
				)
				(justify mirror)
			)
		)
		(property "Val" "1k"
			(at 0 0 0)
			(layer "B.Fab")
			(hide yes)
			(effects
				(font
					(size 1 1)
					(thickness 0.15)
				)
				(justify mirror)
			)
		)
		(sheetname "Ethernet")
		(sheetfile "ethernet.kicad_sch")
		(attr smd)
		(fp_rect
			(start -0.925 0.47)
			(end 0.925 -0.47)
			(stroke
				(width 0.05)
				(type default)
			)
			(fill none)
			(layer "B.CrtYd")
		)
		(fp_rect
			(start -0.5 0.25)
			(end 0.5 -0.25)
			(stroke
				(width 0.15)
				(type solid)
			)
			(fill none)
			(layer "B.Fab")
		)
		(fp_text user "License: Apache-2.0"
			(at -0.95 -5.169 180)
			(layer "B.Fab")
			(hide yes)
			(effects
				(font
					(size 0.7 0.7)
					(thickness 0.15)
				)
				(justify left bottom mirror)
			)
		)
		(fp_text user "Author: Antmicro"
			(at -0.95 -4.169 180)
			(layer "B.Fab")
			(hide yes)
			(effects
				(font
					(size 0.7 0.7)
					(thickness 0.15)
				)
				(justify left bottom mirror)
			)
		)
		(fp_text user "${REFERENCE}"
			(at -0.95 -3.168 180)
			(layer "B.Fab")
			(hide yes)
			(effects
				(font
					(size 0.7 0.7)
					(thickness 0.15)
				)
				(justify left bottom mirror)
			)
		)
		(pad "1" smd roundrect
			(at -0.48 0)
			(size 0.59 0.64)
			(layers "B.Cu" "B.Paste" "B.Mask")
			(roundrect_rratio 0.25)
			(net 731 "Net-(R156-Pad1)")
			(pintype "passive")
		)
		(pad "2" smd roundrect
			(at 0.48 0)
			(size 0.59 0.64)
			(layers "B.Cu" "B.Paste" "B.Mask")
			(roundrect_rratio 0.25)
			(net 1 "GND")
			(pintype "passive")
		)
	)
	(footprint "antmicro-footprints:R_0402_1005Metric"
		(layer "B.Cu")
		(at 65.3 77.5 180)
		(descr "Resistor SMD 0402")
		(tags "resistor SMD 0402")
		(property "Reference" "R260"
			(at -16.94 -3.47 0)
			(layer "B.SilkS")
			(effects
				(font
					(size 0.7 0.7)
					(thickness 0.15)
				)
				(justify left bottom mirror)
			)
		)
		(property "Value" "R_0R_0402"
			(at 0 -1.4 0)
			(layer "B.Fab")
			(effects
				(font
					(size 0.7 0.7)
					(thickness 0.15)
				)
				(justify left bottom mirror)
			)
		)
		(property "Footprint" "antmicro-footprints:R_0402_1005Metric"
			(at 0 0 180)
			(layer "F.Fab")
			(hide yes)
			(effects
				(font
					(size 1.27 1.27)
					(thickness 0.15)
				)
			)
		)
		(property "Datasheet" "https://industrial.panasonic.com/cdbs/www-data/pdf/RDA0000/AOA0000C301.pdf"
			(at 0 0 180)
			(layer "F.Fab")
			(hide yes)
			(effects
				(font
					(size 1.27 1.27)
					(thickness 0.15)
				)
			)
		)
		(property "Author" "Antmicro"
			(at 130.6 155 0)
			(layer "B.Fab")
			(hide yes)
			(effects
				(font
					(size 1 1)
					(thickness 0.15)
				)
				(justify mirror)
			)
		)
		(property "Current" "1A"
			(at 130.6 155 0)
			(layer "B.Fab")
			(hide yes)
			(effects
				(font
					(size 1 1)
					(thickness 0.15)
				)
				(justify mirror)
			)
		)
		(property "License" "Apache-2.0"
			(at 130.6 155 0)
			(layer "B.Fab")
			(hide yes)
			(effects
				(font
					(size 1 1)
					(thickness 0.15)
				)
				(justify mirror)
			)
		)
		(property "MPN" "ERJ2GE0R00X"
			(at 130.6 155 0)
			(layer "B.Fab")
			(hide yes)
			(effects
				(font
					(size 1 1)
					(thickness 0.15)
				)
				(justify mirror)
			)
		)
		(property "Manufacturer" "Panasonic"
			(at 130.6 155 0)
			(layer "B.Fab")
			(hide yes)
			(effects
				(font
					(size 1 1)
					(thickness 0.15)
				)
				(justify mirror)
			)
		)
		(property "Tolerance" ""
			(at 130.6 155 0)
			(layer "B.Fab")
			(hide yes)
			(effects
				(font
					(size 1 1)
					(thickness 0.15)
				)
				(justify mirror)
			)
		)
		(property "Val" "0R"
			(at 130.6 155 0)
			(layer "B.Fab")
			(hide yes)
			(effects
				(font
					(size 1 1)
					(thickness 0.15)
				)
				(justify mirror)
			)
		)
		(sheetname "Supply")
		(sheetfile "supply.kicad_sch")
		(attr smd)
		(fp_rect
			(start -0.925 0.47)
			(end 0.925 -0.47)
			(stroke
				(width 0.05)
				(type default)
			)
			(fill none)
			(layer "B.CrtYd")
		)
		(fp_rect
			(start -0.5 0.25)
			(end 0.5 -0.25)
			(stroke
				(width 0.15)
				(type solid)
			)
			(fill none)
			(layer "B.Fab")
		)
		(fp_text user "Author: Antmicro"
			(at -0.95 -4.169 0)
			(layer "B.Fab")
			(hide yes)
			(effects
				(font
					(size 0.7 0.7)
					(thickness 0.15)
				)
				(justify left bottom mirror)
			)
		)
		(fp_text user "${REFERENCE}"
			(at -0.95 -3.168 0)
			(layer "B.Fab")
			(hide yes)
			(effects
				(font
					(size 0.7 0.7)
					(thickness 0.15)
				)
				(justify left bottom mirror)
			)
		)
		(fp_text user "License: Apache-2.0"
			(at -0.95 -5.169 0)
			(layer "B.Fab")
			(hide yes)
			(effects
				(font
					(size 0.7 0.7)
					(thickness 0.15)
				)
				(justify left bottom mirror)
			)
		)
		(pad "1" smd roundrect
			(at -0.48 0 180)
			(size 0.59 0.64)
			(layers "B.Cu" "B.Paste" "B.Mask")
			(roundrect_rratio 0.25)
			(net 689 "Net-(U38-Q)")
			(pintype "passive")
		)
		(pad "2" smd roundrect
			(at 0.48 0 180)
			(size 0.59 0.64)
			(layers "B.Cu" "B.Paste" "B.Mask")
			(roundrect_rratio 0.25)
			(net 476 "POWER_EN")
			(pintype "passive")
		)
	)
	(footprint "antmicro-footprints:R_0603_1608Metric"
		(layer "B.Cu")
		(at 43.575 69.8 180)
		(descr "Resistor SMD 0603")
		(tags "resistor SMD 0603")
		(property "Reference" "R157"
			(at -4.065 -0.34 0)
			(layer "B.SilkS")
			(effects
				(font
					(size 0.7 0.7)
					(thickness 0.15)
				)
				(justify left bottom mirror)
			)
		)
		(property "Value" "R_0R_0603"
			(at 0 -1.6 0)
			(layer "B.Fab")
			(effects
				(font
					(size 0.7 0.7)
					(thickness 0.15)
				)
				(justify left bottom mirror)
			)
		)
		(property "Footprint" "antmicro-footprints:R_0603_1608Metric"
			(at 0 0 180)
			(layer "F.Fab")
			(hide yes)
			(effects
				(font
					(size 1.27 1.27)
					(thickness 0.15)
				)
			)
		)
		(property "Datasheet" "https://www.bourns.com/docs/product-datasheets/cr.pdf?sfvrsn=574d41f6_14"
			(at 0 0 180)
			(layer "F.Fab")
			(hide yes)
			(effects
				(font
					(size 1.27 1.27)
					(thickness 0.15)
				)
			)
		)
		(property "Author" "Antmicro"
			(at 87.15 139.6 0)
			(layer "B.Fab")
			(hide yes)
			(effects
				(font
					(size 1 1)
					(thickness 0.15)
				)
				(justify mirror)
			)
		)
		(property "Current" "1A"
			(at 87.15 139.6 0)
			(layer "B.Fab")
			(hide yes)
			(effects
				(font
					(size 1 1)
					(thickness 0.15)
				)
				(justify mirror)
			)
		)
		(property "License" "Apache-2.0"
			(at 87.15 139.6 0)
			(layer "B.Fab")
			(hide yes)
			(effects
				(font
					(size 1 1)
					(thickness 0.15)
				)
				(justify mirror)
			)
		)
		(property "MPN" "CR0603-J/-000ELF"
			(at 87.15 139.6 0)
			(layer "B.Fab")
			(hide yes)
			(effects
				(font
					(size 1 1)
					(thickness 0.15)
				)
				(justify mirror)
			)
		)
		(property "Manufacturer" "Bourns"
			(at 87.15 139.6 0)
			(layer "B.Fab")
			(hide yes)
			(effects
				(font
					(size 1 1)
					(thickness 0.15)
				)
				(justify mirror)
			)
		)
		(property "Tolerance" ""
			(at 87.15 139.6 0)
			(layer "B.Fab")
			(hide yes)
			(effects
				(font
					(size 1 1)
					(thickness 0.15)
				)
				(justify mirror)
			)
		)
		(property "Val" "0R"
			(at 87.15 139.6 0)
			(layer "B.Fab")
			(hide yes)
			(effects
				(font
					(size 1 1)
					(thickness 0.15)
				)
				(justify mirror)
			)
		)
		(sheetname "Ethernet")
		(sheetfile "ethernet.kicad_sch")
		(attr smd exclude_from_pos_files exclude_from_bom dnp)
		(fp_line
			(start 0.15 0.4)
			(end -0.15 0.4)
			(stroke
				(width 0.15)
				(type solid)
			)
			(layer "B.SilkS")
		)
		(fp_line
			(start 0.15 -0.4)
			(end -0.15 -0.4)
			(stroke
				(width 0.15)
				(type solid)
			)
			(layer "B.SilkS")
		)
		(fp_rect
			(start -1.25 0.65)
			(end 1.25 -0.65)
			(stroke
				(width 0.05)
				(type solid)
			)
			(fill none)
			(layer "B.CrtYd")
		)
		(fp_rect
			(start -0.8 0.4)
			(end 0.8 -0.4)
			(stroke
				(width 0.15)
				(type solid)
			)
			(fill none)
			(layer "B.Fab")
		)
		(fp_text user "${REFERENCE}"
			(at -1.25 -3.898 0)
			(layer "B.Fab")
			(hide yes)
			(effects
				(font
					(size 0.7 0.7)
					(thickness 0.15)
				)
				(justify left bottom mirror)
			)
		)
		(fp_text user "Author: Antmicro"
			(at -1.25 -4.9 0)
			(layer "B.Fab")
			(hide yes)
			(effects
				(font
					(size 0.7 0.7)
					(thickness 0.15)
				)
				(justify left bottom mirror)
			)
		)
		(fp_text user "License: Apache-2.0"
			(at -1.25 -5.9 0)
			(layer "B.Fab")
			(hide yes)
			(effects
				(font
					(size 0.7 0.7)
					(thickness 0.15)
				)
				(justify left bottom mirror)
			)
		)
		(pad "1" smd roundrect
			(at -0.7 0 180)
			(size 0.8 1)
			(layers "B.Cu" "B.Paste" "B.Mask")
			(roundrect_rratio 0.2)
			(net 1 "GND")
			(pintype "passive")
		)
		(pad "2" smd roundrect
			(at 0.7 0 180)
			(size 0.8 1)
			(layers "B.Cu" "B.Paste" "B.Mask")
			(roundrect_rratio 0.2)
			(net 683 "Net-(U23-TRIM)")
			(pintype "passive")
		)
	)
)
